# T6G (Grand Teton) — schematic netlist excerpt (pin names and nets, part order shuffled) for the footprints in the layout excerpt that follows; sources: Cadence DE-HDL packaged netlist, KiCad conversion of 04192023_DAF0TMB3IC0_F0TG_MB_C_brd_V02_OCP.brd

C246  Q_CAP  22UF 4V 20% X6S  pkg C0402  page 69 : A = PVDDCR_CPU0_P0 ; B = GND
C2631  Q_CAP  22UF 4V 20% X6S  pkg C0402  page 70 : A = PVDDIO_P0 ; B = GND
C6729  Q_CAP_DIFFBUS  DIFF BUS_0.22UF 6.3V 20% X6S  pkg C0201  page 352 : \1\ = P5E_CPU1_P3_TX_BUF_C_DP<2> ; \2\ = P5E_CPU1_P3_TX_BUF_DP<2>

(kicad_pcb
	(version 20260206)
	(generator "pcbnew")
	(generator_version "10.0")
	(general
		(thickness 1.6)
		(legacy_teardrops no)
	)
	(paper "A4")
	(title_block
		(title "04192023_DAF0TMB3IC0_F0TG_MB_C_brd_V02_OCP.brd")
		(comment 1 "Grand Teton / footprints 7647-7649 of 8354")
	)
	(layers
		(0 "F.Cu" signal "TOP")
		(4 "In1.Cu" signal "GND")
		(6 "In2.Cu" signal "IN1")
		(8 "In3.Cu" signal "GND1")
		(10 "In4.Cu" signal "IN2")
		(12 "In5.Cu" signal "GND2")
		(14 "In6.Cu" signal "IN3")
		(16 "In7.Cu" signal "GND3")
		(18 "In8.Cu" signal "VCC")
		(20 "In9.Cu" signal "VCC1")
		(22 "In10.Cu" signal "GND4")
		(24 "In11.Cu" signal "IN4")
		(26 "In12.Cu" signal "GND5")
		(28 "In13.Cu" signal "IN5")
		(30 "In14.Cu" signal "GND6")
		(32 "In15.Cu" signal "IN6")
		(34 "In16.Cu" signal "GND7")
		(2 "B.Cu" signal "BOTTOM")
		(9 "F.Adhes" user "F.Adhesive")
		(11 "B.Adhes" user "B.Adhesive")
		(13 "F.Paste" user "Package Geometry/Pastemask Top")
		(15 "B.Paste" user "Package Geometry/Pastemask Bottom")
		(5 "F.SilkS" user "Ref Des/Silkscreen Top")
		(7 "B.SilkS" user "Ref Des/Silkscreen Bottom")
		(1 "F.Mask" user "Board Geometry/Soldermask Top")
		(3 "B.Mask" user "Board Geometry/Soldermask Bottom")
		(17 "Dwgs.User" user "User.Drawings")
		(19 "Cmts.User" user "User.Comments")
		(21 "Eco1.User" user "User.Eco1")
		(23 "Eco2.User" user "User.Eco2")
		(25 "Edge.Cuts" user "Board Geometry/Outline")
		(27 "Margin" user)
		(31 "F.CrtYd" user "Package Geometry/Place Bound Top")
		(29 "B.CrtYd" user "Package Geometry/Place Bound Bottom")
		(35 "F.Fab" user "Ref Des/Assembly Top")
		(33 "B.Fab" user "Ref Des/Assembly Bottom")
	)
	(footprint ""
		(layer "B.Cu")
		(at 363.931454 -249.36831)
		(property "Reference" "C246"
			(at 0 0 0)
			(layer "B.SilkS")
			(hide yes)
			(effects
				(font
					(size 1.27 1.27)
				)
				(justify mirror)
			)
		)
		(property "Value" ""
			(at 0 0 0)
			(layer "B.Fab")
			(effects
				(font
					(size 1.27 1.27)
				)
				(justify mirror)
			)
		)
		(duplicate_pad_numbers_are_jumpers no)
		(fp_line
			(start -0.7874 -0.4064)
			(end -0.7874 0.4064)
			(stroke
				(width 0.1524)
				(type default)
			)
			(layer "B.SilkS")
		)
		(fp_line
			(start -0.7874 0.4064)
			(end 0.7874 0.4064)
			(stroke
				(width 0.1524)
				(type default)
			)
			(layer "B.SilkS")
		)
		(fp_line
			(start 0.7874 -0.4064)
			(end -0.7874 -0.4064)
			(stroke
				(width 0.1524)
				(type default)
			)
			(layer "B.SilkS")
		)
		(fp_line
			(start 0.7874 0.4064)
			(end 0.7874 -0.4064)
			(stroke
				(width 0.1524)
				(type default)
			)
			(layer "B.SilkS")
		)
		(fp_line
			(start -0.67945 -0.3048)
			(end -0.67945 0.3048)
			(stroke
				(width 0.1)
				(type default)
			)
			(layer "B.Fab")
		)
		(fp_line
			(start -0.67945 0.3048)
			(end -0.120396 0.3048)
			(stroke
				(width 0.1)
				(type default)
			)
			(layer "B.Fab")
		)
		(fp_line
			(start -0.12065 -0.3048)
			(end -0.67945 -0.3048)
			(stroke
				(width 0.1)
				(type default)
			)
			(layer "B.Fab")
		)
		(fp_line
			(start -0.12065 -0.2794)
			(end -0.12065 -0.3048)
			(stroke
				(width 0.1)
				(type default)
			)
			(layer "B.Fab")
		)
		(fp_line
			(start -0.120396 0.2794)
			(end 0.12065 0.2794)
			(stroke
				(width 0.1)
				(type default)
			)
			(layer "B.Fab")
		)
		(fp_line
			(start -0.120396 0.3048)
			(end -0.120396 0.2794)
			(stroke
				(width 0.1)
				(type default)
			)
			(layer "B.Fab")
		)
		(fp_line
			(start 0.12065 -0.305054)
			(end 0.12065 -0.2794)
			(stroke
				(width 0.1)
				(type default)
			)
			(layer "B.Fab")
		)
		(fp_line
			(start 0.12065 -0.2794)
			(end -0.12065 -0.2794)
			(stroke
				(width 0.1)
				(type default)
			)
			(layer "B.Fab")
		)
		(fp_line
			(start 0.12065 0.2794)
			(end 0.12065 0.3048)
			(stroke
				(width 0.1)
				(type default)
			)
			(layer "B.Fab")
		)
		(fp_line
			(start 0.12065 0.3048)
			(end 0.67945 0.3048)
			(stroke
				(width 0.1)
				(type default)
			)
			(layer "B.Fab")
		)
		(fp_line
			(start 0.67945 -0.305054)
			(end 0.12065 -0.305054)
			(stroke
				(width 0.1)
				(type default)
			)
			(layer "B.Fab")
		)
		(fp_line
			(start 0.67945 0.3048)
			(end 0.67945 -0.305054)
			(stroke
				(width 0.1)
				(type default)
			)
			(layer "B.Fab")
		)
		(pad "1" smd circle
			(at 0.40005 0 180)
			(size 0 0)
			(layers "B.Cu" "B.Mask" "B.Paste")
			(net "PVDDCR_CPU0_P0")
		)
		(pad "2" smd circle
			(at -0.40005 0 180)
			(size 0 0)
			(layers "B.Cu" "B.Mask" "B.Paste")
			(net "GND")
		)
	)
	(footprint ""
		(layer "B.Cu")
		(at 348.418912 -259.729986 180)
		(property "Reference" "C2631"
			(at 0 0 0)
			(layer "B.SilkS")
			(hide yes)
			(effects
				(font
					(size 1.27 1.27)
				)
				(justify mirror)
			)
		)
		(property "Value" ""
			(at 0 0 0)
			(layer "B.Fab")
			(effects
				(font
					(size 1.27 1.27)
				)
				(justify mirror)
			)
		)
		(duplicate_pad_numbers_are_jumpers no)
		(fp_line
			(start 0.7874 0.4064)
			(end 0.7874 -0.4064)
			(stroke
				(width 0.1524)
				(type default)
			)
			(layer "B.SilkS")
		)
		(fp_line
			(start 0.7874 -0.4064)
			(end -0.7874 -0.4064)
			(stroke
				(width 0.1524)
				(type default)
			)
			(layer "B.SilkS")
		)
		(fp_line
			(start -0.7874 0.4064)
			(end 0.7874 0.4064)
			(stroke
				(width 0.1524)
				(type default)
			)
			(layer "B.SilkS")
		)
		(fp_line
			(start -0.7874 -0.4064)
			(end -0.7874 0.4064)
			(stroke
				(width 0.1524)
				(type default)
			)
			(layer "B.SilkS")
		)
		(fp_line
			(start 0.67945 0.3048)
			(end 0.67945 -0.305054)
			(stroke
				(width 0.1)
				(type default)
			)
			(layer "B.Fab")
		)
		(fp_line
			(start 0.67945 -0.305054)
			(end 0.12065 -0.305054)
			(stroke
				(width 0.1)
				(type default)
			)
			(layer "B.Fab")
		)
		(fp_line
			(start 0.12065 0.3048)
			(end 0.67945 0.3048)
			(stroke
				(width 0.1)
				(type default)
			)
			(layer "B.Fab")
		)
		(fp_line
			(start 0.12065 0.2794)
			(end 0.12065 0.3048)
			(stroke
				(width 0.1)
				(type default)
			)
			(layer "B.Fab")
		)
		(fp_line
			(start 0.12065 -0.2794)
			(end -0.12065 -0.2794)
			(stroke
				(width 0.1)
				(type default)
			)
			(layer "B.Fab")
		)
		(fp_line
			(start 0.12065 -0.305054)
			(end 0.12065 -0.2794)
			(stroke
				(width 0.1)
				(type default)
			)
			(layer "B.Fab")
		)
		(fp_line
			(start -0.120396 0.3048)
			(end -0.120396 0.2794)
			(stroke
				(width 0.1)
				(type default)
			)
			(layer "B.Fab")
		)
		(fp_line
			(start -0.120396 0.2794)
			(end 0.12065 0.2794)
			(stroke
				(width 0.1)
				(type default)
			)
			(layer "B.Fab")
		)
		(fp_line
			(start -0.12065 -0.2794)
			(end -0.12065 -0.3048)
			(stroke
				(width 0.1)
				(type default)
			)
			(layer "B.Fab")
		)
		(fp_line
			(start -0.12065 -0.3048)
			(end -0.67945 -0.3048)
			(stroke
				(width 0.1)
				(type default)
			)
			(layer "B.Fab")
		)
		(fp_line
			(start -0.67945 0.3048)
			(end -0.120396 0.3048)
			(stroke
				(width 0.1)
				(type default)
			)
			(layer "B.Fab")
		)
		(fp_line
			(start -0.67945 -0.3048)
			(end -0.67945 0.3048)
			(stroke
				(width 0.1)
				(type default)
			)
			(layer "B.Fab")
		)
		(pad "1" smd circle
			(at 0.40005 0)
			(size 0 0)
			(layers "B.Cu" "B.Mask" "B.Paste")
			(net "PVDDIO_P0")
		)
		(pad "2" smd circle
			(at -0.40005 0)
			(size 0 0)
			(layers "B.Cu" "B.Mask" "B.Paste")
			(net "GND")
		)
	)
	(footprint ""
		(layer "B.Cu")
		(at 123.441206 -408.517344 90)
		(property "Reference" "C6729"
			(at 0 0 90)
			(layer "B.SilkS")
			(hide yes)
			(effects
				(font
					(size 1.27 1.27)
				)
				(justify mirror)
			)
		)
		(property "Value" ""
			(at 0 0 90)
			(layer "B.Fab")
			(effects
				(font
					(size 1.27 1.27)
				)
				(justify mirror)
			)
		)
		(duplicate_pad_numbers_are_jumpers no)
		(fp_line
			(start 0.299974 -0.150114)
			(end -0.299974 -0.150114)
			(stroke
				(width 0.1)
				(type default)
			)
			(layer "B.Fab")
		)
		(fp_line
			(start -0.299974 -0.150114)
			(end -0.299974 0.150114)
			(stroke
				(width 0.1)
				(type default)
			)
			(layer "B.Fab")
		)
		(fp_line
			(start 0.299974 0.150114)
			(end 0.299974 -0.150114)
			(stroke
				(width 0.1)
				(type default)
			)
			(layer "B.Fab")
		)
		(fp_line
			(start -0.299974 0.150114)
			(end 0.299974 0.150114)
			(stroke
				(width 0.1)
				(type default)
			)
			(layer "B.Fab")
		)
		(pad "1" smd rect
			(at 0.2667 0 270)
			(size 0.3048 0.381)
			(layers "B.Cu" "B.Mask" "B.Paste")
			(net "P5E_CPU1_P3_TX_BUF_C_DP<2>")
		)
		(pad "2" smd rect
			(at -0.2667 0 270)
			(size 0.3048 0.381)
			(layers "B.Cu" "B.Mask" "B.Paste")
			(net "P5E_CPU1_P3_TX_BUF_DP<2>")
		)
	)
)
